# T6G (Grand Teton) — schematic netlist excerpt (pin names and nets, part order shuffled) for the footprints in the layout excerpt that follows; sources: Cadence DE-HDL packaged netlist, KiCad conversion of 04192023_DAF0TMB3IC0_F0TG_MB_C_brd_V02_OCP.brd

R1182  Q_RES  0 5% EMPTY  pkg 0402LF  page 140 : A = HP_LVC3_OCP_V3_2_P12V_PWRGD ; B = P3V3_OCP_EN_2_R
R4491  Q_RES  10K 1% CHIP  pkg 0402LF  page 182 : A = P3V3_AUX ; B = CLK_9ZXL045_P0_HIBW
C6580  Q_CAP_DIFFBUS  DIFF BUS_0.22UF 6.3V 20% X6S  pkg C0201  page 297 : \1\ = P5E_CPU0_P2_TX_BUF_C_DN<7> ; \2\ = P5E_CPU0_P2_TX_BUF_DN<7>

(kicad_pcb
	(version 20260206)
	(generator "pcbnew")
	(generator_version "10.0")
	(general
		(thickness 1.6)
		(legacy_teardrops no)
	)
	(paper "A4")
	(title_block
		(title "04192023_DAF0TMB3IC0_F0TG_MB_C_brd_V02_OCP.brd")
		(comment 1 "Grand Teton / footprints 3633-3635 of 8354")
	)
	(layers
		(0 "F.Cu" signal "TOP")
		(4 "In1.Cu" signal "GND")
		(6 "In2.Cu" signal "IN1")
		(8 "In3.Cu" signal "GND1")
		(10 "In4.Cu" signal "IN2")
		(12 "In5.Cu" signal "GND2")
		(14 "In6.Cu" signal "IN3")
		(16 "In7.Cu" signal "GND3")
		(18 "In8.Cu" signal "VCC")
		(20 "In9.Cu" signal "VCC1")
		(22 "In10.Cu" signal "GND4")
		(24 "In11.Cu" signal "IN4")
		(26 "In12.Cu" signal "GND5")
		(28 "In13.Cu" signal "IN5")
		(30 "In14.Cu" signal "GND6")
		(32 "In15.Cu" signal "IN6")
		(34 "In16.Cu" signal "GND7")
		(2 "B.Cu" signal "BOTTOM")
		(9 "F.Adhes" user "F.Adhesive")
		(11 "B.Adhes" user "B.Adhesive")
		(13 "F.Paste" user "Package Geometry/Pastemask Top")
		(15 "B.Paste" user "Package Geometry/Pastemask Bottom")
		(5 "F.SilkS" user "Ref Des/Silkscreen Top")
		(7 "B.SilkS" user "Ref Des/Silkscreen Bottom")
		(1 "F.Mask" user "Board Geometry/Soldermask Top")
		(3 "B.Mask" user "Board Geometry/Soldermask Bottom")
		(17 "Dwgs.User" user "User.Drawings")
		(19 "Cmts.User" user "User.Comments")
		(21 "Eco1.User" user "User.Eco1")
		(23 "Eco2.User" user "User.Eco2")
		(25 "Edge.Cuts" user "Board Geometry/Outline")
		(27 "Margin" user)
		(31 "F.CrtYd" user "Package Geometry/Place Bound Top")
		(29 "B.CrtYd" user "Package Geometry/Place Bound Bottom")
		(35 "F.Fab" user "Ref Des/Assembly Top")
		(33 "B.Fab" user "Ref Des/Assembly Bottom")
	)
	(footprint ""
		(layer "F.Cu")
		(at 392.311382 -416.899344 -90)
		(property "Reference" "C6580"
			(at 0 0 270)
			(layer "F.SilkS")
			(hide yes)
			(effects
				(font
					(size 1.27 1.27)
				)
			)
		)
		(property "Value" ""
			(at 0 0 270)
			(layer "F.Fab")
			(effects
				(font
					(size 1.27 1.27)
				)
			)
		)
		(duplicate_pad_numbers_are_jumpers no)
		(fp_line
			(start -0.299974 0.150114)
			(end -0.299974 -0.150114)
			(stroke
				(width 0.1)
				(type default)
			)
			(layer "F.Fab")
		)
		(fp_line
			(start 0.299974 0.150114)
			(end -0.299974 0.150114)
			(stroke
				(width 0.1)
				(type default)
			)
			(layer "F.Fab")
		)
		(fp_line
			(start -0.299974 -0.150114)
			(end 0.299974 -0.150114)
			(stroke
				(width 0.1)
				(type default)
			)
			(layer "F.Fab")
		)
		(fp_line
			(start 0.299974 -0.150114)
			(end 0.299974 0.150114)
			(stroke
				(width 0.1)
				(type default)
			)
			(layer "F.Fab")
		)
		(pad "1" smd rect
			(at -0.2667 0 270)
			(size 0.3048 0.381)
			(layers "F.Cu" "F.Mask" "F.Paste")
			(net "P5E_CPU0_P2_TX_BUF_C_DN<7>")
		)
		(pad "2" smd rect
			(at 0.2667 0 270)
			(size 0.3048 0.381)
			(layers "F.Cu" "F.Mask" "F.Paste")
			(net "P5E_CPU0_P2_TX_BUF_DN<7>")
		)
	)
	(footprint ""
		(layer "F.Cu")
		(at 58.297064 -39.003986 90)
		(property "Reference" "R1182"
			(at 0 0 90)
			(layer "F.SilkS")
			(hide yes)
			(effects
				(font
					(size 1.27 1.27)
				)
			)
		)
		(property "Value" ""
			(at 0 0 90)
			(layer "F.Fab")
			(effects
				(font
					(size 1.27 1.27)
				)
			)
		)
		(duplicate_pad_numbers_are_jumpers no)
		(fp_line
			(start 0.7874 -0.4064)
			(end 0.7874 0.4064)
			(stroke
				(width 0.1524)
				(type default)
			)
			(layer "F.SilkS")
		)
		(fp_line
			(start -0.7874 -0.4064)
			(end 0.7874 -0.4064)
			(stroke
				(width 0.1524)
				(type default)
			)
			(layer "F.SilkS")
		)
		(fp_line
			(start 0.7874 0.4064)
			(end -0.7874 0.4064)
			(stroke
				(width 0.1524)
				(type default)
			)
			(layer "F.SilkS")
		)
		(fp_line
			(start -0.7874 0.4064)
			(end -0.7874 -0.4064)
			(stroke
				(width 0.1524)
				(type default)
			)
			(layer "F.SilkS")
		)
		(fp_line
			(start -0.12065 -0.305054)
			(end -0.12065 -0.2794)
			(stroke
				(width 0.1)
				(type default)
			)
			(layer "F.Fab")
		)
		(fp_line
			(start -0.67945 -0.305054)
			(end -0.12065 -0.305054)
			(stroke
				(width 0.1)
				(type default)
			)
			(layer "F.Fab")
		)
		(fp_line
			(start 0.67945 -0.3048)
			(end 0.67945 0.3048)
			(stroke
				(width 0.1)
				(type default)
			)
			(layer "F.Fab")
		)
		(fp_line
			(start 0.12065 -0.3048)
			(end 0.67945 -0.3048)
			(stroke
				(width 0.1)
				(type default)
			)
			(layer "F.Fab")
		)
		(fp_line
			(start 0.12065 -0.2794)
			(end 0.12065 -0.3048)
			(stroke
				(width 0.1)
				(type default)
			)
			(layer "F.Fab")
		)
		(fp_line
			(start -0.12065 -0.2794)
			(end 0.12065 -0.2794)
			(stroke
				(width 0.1)
				(type default)
			)
			(layer "F.Fab")
		)
		(fp_line
			(start 0.120396 0.2794)
			(end -0.12065 0.2794)
			(stroke
				(width 0.1)
				(type default)
			)
			(layer "F.Fab")
		)
		(fp_line
			(start -0.12065 0.2794)
			(end -0.12065 0.3048)
			(stroke
				(width 0.1)
				(type default)
			)
			(layer "F.Fab")
		)
		(fp_line
			(start 0.67945 0.3048)
			(end 0.120396 0.3048)
			(stroke
				(width 0.1)
				(type default)
			)
			(layer "F.Fab")
		)
		(fp_line
			(start 0.120396 0.3048)
			(end 0.120396 0.2794)
			(stroke
				(width 0.1)
				(type default)
			)
			(layer "F.Fab")
		)
		(fp_line
			(start -0.12065 0.3048)
			(end -0.67945 0.3048)
			(stroke
				(width 0.1)
				(type default)
			)
			(layer "F.Fab")
		)
		(fp_line
			(start -0.67945 0.3048)
			(end -0.67945 -0.305054)
			(stroke
				(width 0.1)
				(type default)
			)
			(layer "F.Fab")
		)
		(pad "1" smd circle
			(at -0.40005 0 90)
			(size 0 0)
			(layers "F.Cu" "F.Mask" "F.Paste")
			(net "HP_LVC3_OCP_V3_2_P12V_PWRGD")
		)
		(pad "2" smd circle
			(at 0.40005 0 90)
			(size 0 0)
			(layers "F.Cu" "F.Mask" "F.Paste")
			(net "P3V3_OCP_EN_2_R")
		)
	)
	(footprint ""
		(layer "F.Cu")
		(at 282.575 -423.418 -90)
		(property "Reference" "R4491"
			(at 0 0 270)
			(layer "F.SilkS")
			(hide yes)
			(effects
				(font
					(size 1.27 1.27)
				)
			)
		)
		(property "Value" ""
			(at 0 0 270)
			(layer "F.Fab")
			(effects
				(font
					(size 1.27 1.27)
				)
			)
		)
		(duplicate_pad_numbers_are_jumpers no)
		(fp_line
			(start -0.7874 0.4064)
			(end -0.7874 -0.4064)
			(stroke
				(width 0.1524)
				(type default)
			)
			(layer "F.SilkS")
		)
		(fp_line
			(start 0.7874 0.4064)
			(end -0.7874 0.4064)
			(stroke
				(width 0.1524)
				(type default)
			)
			(layer "F.SilkS")
		)
		(fp_line
			(start -0.7874 -0.4064)
			(end 0.7874 -0.4064)
			(stroke
				(width 0.1524)
				(type default)
			)
			(layer "F.SilkS")
		)
		(fp_line
			(start 0.7874 -0.4064)
			(end 0.7874 0.4064)
			(stroke
				(width 0.1524)
				(type default)
			)
			(layer "F.SilkS")
		)
		(fp_line
			(start -0.67945 0.3048)
			(end -0.67945 -0.305054)
			(stroke
				(width 0.1)
				(type default)
			)
			(layer "F.Fab")
		)
		(fp_line
			(start -0.12065 0.3048)
			(end -0.67945 0.3048)
			(stroke
				(width 0.1)
				(type default)
			)
			(layer "F.Fab")
		)
		(fp_line
			(start 0.120396 0.3048)
			(end 0.120396 0.2794)
			(stroke
				(width 0.1)
				(type default)
			)
			(layer "F.Fab")
		)
		(fp_line
			(start 0.67945 0.3048)
			(end 0.120396 0.3048)
			(stroke
				(width 0.1)
				(type default)
			)
			(layer "F.Fab")
		)
		(fp_line
			(start -0.12065 0.2794)
			(end -0.12065 0.3048)
			(stroke
				(width 0.1)
				(type default)
			)
			(layer "F.Fab")
		)
		(fp_line
			(start 0.120396 0.2794)
			(end -0.12065 0.2794)
			(stroke
				(width 0.1)
				(type default)
			)
			(layer "F.Fab")
		)
		(fp_line
			(start -0.12065 -0.2794)
			(end 0.12065 -0.2794)
			(stroke
				(width 0.1)
				(type default)
			)
			(layer "F.Fab")
		)
		(fp_line
			(start 0.12065 -0.2794)
			(end 0.12065 -0.3048)
			(stroke
				(width 0.1)
				(type default)
			)
			(layer "F.Fab")
		)
		(fp_line
			(start 0.12065 -0.3048)
			(end 0.67945 -0.3048)
			(stroke
				(width 0.1)
				(type default)
			)
			(layer "F.Fab")
		)
		(fp_line
			(start 0.67945 -0.3048)
			(end 0.67945 0.3048)
			(stroke
				(width 0.1)
				(type default)
			)
			(layer "F.Fab")
		)
		(fp_line
			(start -0.67945 -0.305054)
			(end -0.12065 -0.305054)
			(stroke
				(width 0.1)
				(type default)
			)
			(layer "F.Fab")
		)
		(fp_line
			(start -0.12065 -0.305054)
			(end -0.12065 -0.2794)
			(stroke
				(width 0.1)
				(type default)
			)
			(layer "F.Fab")
		)
		(pad "1" smd circle
			(at -0.40005 0 270)
			(size 0 0)
			(layers "F.Cu" "F.Mask" "F.Paste")
			(net "P3V3_AUX")
		)
		(pad "2" smd circle
			(at 0.40005 0 270)
			(size 0 0)
			(layers "F.Cu" "F.Mask" "F.Paste")
			(net "CLK_9ZXL045_P0_HIBW")
		)
	)
)
